INTEGER-PLACES         2
DECIMAL-PLACES         5
X-OFFSET               0.000000
Y-OFFSET               0.000000
FEEDRATE               1
COORDINATES            ABSOLUTE
OUTPUT-UNITS           ENGLISH
TOOL-ORDER             INCREASING
REPEAT-CODES           NO
SUPPRESS-LEAD-ZEROES   NO
SUPPRESS-TRAIL-ZEROES  NO
SUPPRESS-EQUAL         NO
TOOL-SELECT            NO
OPTIMIZE_DRILLING      NO
ENHANCED_EXCELLON      NO
HEADER                 none
LEADER                 12
CODE                   ASCII
SEPARATE               NO
SEPARATE-ROUTING       NO
DRILLING               LAYER-PAIR
BACKDRILL              NO
CAVITY                 NO
COUNTER                NO
TOLERANCE_DRILL        NO
TOLERANCE_TRAVEL       NO
TOOL_SIZE              NO
ROTATION               NO
NON_STANDARD           NO
TOTAL_DRILL            NO
SEPARATE_SLOT          NO
SUPPRESS_TOLERANCE     NO
SUPPRESS_TOOLSIZE      NO
SUPPRESS_ROTATION      NO
